(kicad_pcb
	(version 20240108)
	(generator "pcbnew")
	(generator_version "8.0")
	(general
		(thickness 1.6)
		(legacy_teardrops no)
	)
	(paper "A4")
	(title_block
		(title "Jetson Orin Baseboard OCuLink Expansion")
		(date "2025-03-18")
		(rev "1.1.0")
		(company "Antmicro Ltd")
		(comment 1 "www.antmicro.com")
		(comment 9 "footprints 23-24 of 119")
	)
	(layers
		(0 "F.Cu" signal)
		(1 "In1.Cu" signal)
		(2 "In2.Cu" signal)
		(31 "B.Cu" signal)
		(32 "B.Adhes" user "B.Adhesive")
		(33 "F.Adhes" user "F.Adhesive")
		(34 "B.Paste" user)
		(35 "F.Paste" user)
		(36 "B.SilkS" user "B.Silkscreen")
		(37 "F.SilkS" user "F.Silkscreen")
		(38 "B.Mask" user)
		(39 "F.Mask" user)
		(40 "Dwgs.User" user "User.Drawings")
		(41 "Cmts.User" user "User.Comments")
		(42 "Eco1.User" user "User.Eco1")
		(43 "Eco2.User" user "User.Eco2")
		(44 "Edge.Cuts" user)
		(45 "Margin" user)
		(46 "B.CrtYd" user "B.Courtyard")
		(47 "F.CrtYd" user "F.Courtyard")
		(48 "B.Fab" user)
		(49 "F.Fab" user)
	)
	(footprint "antmicro-footprints:C_0402_1005Metric"
		(layer "F.Cu")
		(at 115.43875 137.65 -90)
		(descr "Capacitor SMD 0402")
		(tags "capacitor SMD 0402")
		(property "Reference" "C15"
			(at 0.85 0.30875 90)
			(layer "F.SilkS")
			(effects
				(font
					(size 0.7 0.7)
					(thickness 0.15)
				)
				(justify right top)
			)
		)
		(property "Value" "C_220n_0402"
			(at -1.022927 2.155213 90)
			(layer "F.Fab")
			(effects
				(font
					(size 0.7 0.7)
					(thickness 0.15)
				)
				(justify right top)
			)
		)
		(property "Footprint" "antmicro-footprints:C_0402_1005Metric"
			(at 0 0 90)
			(layer "F.Fab")
			(hide yes)
			(effects
				(font
					(size 1.27 1.27)
					(thickness 0.15)
				)
			)
		)
		(property "Datasheet" "https://www.yageo.com/en/Chart/Download/pdf/CC0402KRX5R6BB224"
			(at 0 0 90)
			(layer "F.Fab")
			(hide yes)
			(effects
				(font
					(size 1.27 1.27)
					(thickness 0.15)
				)
			)
		)
		(property "Description" "SMD Multilayer Ceramic Capacitor, 0.22 µF, 10 V, 0402 [1005 Metric], ± 10%, X5R, CC Series"
			(at 0 0 90)
			(layer "F.Fab")
			(hide yes)
			(effects
				(font
					(size 1.27 1.27)
					(thickness 0.15)
				)
			)
		)
		(property "MPN" "CC0402KRX5R6BB224"
			(at 0 0 -90)
			(unlocked yes)
			(layer "F.Fab")
			(hide yes)
			(effects
				(font
					(size 1 1)
					(thickness 0.15)
				)
			)
		)
		(property "Manufacturer" "YAGEO"
			(at 0 0 -90)
			(unlocked yes)
			(layer "F.Fab")
			(hide yes)
			(effects
				(font
					(size 1 1)
					(thickness 0.15)
				)
			)
		)
		(property "License" "Apache-2.0"
			(at 0 0 -90)
			(unlocked yes)
			(layer "F.Fab")
			(hide yes)
			(effects
				(font
					(size 1 1)
					(thickness 0.15)
				)
			)
		)
		(property "Author" "Antmicro"
			(at 0 0 -90)
			(unlocked yes)
			(layer "F.Fab")
			(hide yes)
			(effects
				(font
					(size 1 1)
					(thickness 0.15)
				)
			)
		)
		(property "Val" "220n"
			(at 0 0 -90)
			(unlocked yes)
			(layer "F.Fab")
			(hide yes)
			(effects
				(font
					(size 1 1)
					(thickness 0.15)
				)
			)
		)
		(property "Voltage" ""
			(at 0 0 -90)
			(unlocked yes)
			(layer "F.Fab")
			(hide yes)
			(effects
				(font
					(size 1 1)
					(thickness 0.15)
				)
			)
		)
		(property "Dielectric" ""
			(at 0 0 -90)
			(unlocked yes)
			(layer "F.Fab")
			(hide yes)
			(effects
				(font
					(size 1 1)
					(thickness 0.15)
				)
			)
		)
		(property "Public" "False"
			(at 0 0 -90)
			(unlocked yes)
			(layer "F.Fab")
			(hide yes)
			(effects
				(font
					(size 1 1)
					(thickness 0.15)
				)
			)
		)
		(sheetname "Root")
		(sheetfile "jetson-orin-baseboard-oculink-expansion.kicad_sch")
		(attr smd)
		(fp_rect
			(start -0.925 -0.47)
			(end 0.925 0.47)
			(stroke
				(width 0.05)
				(type default)
			)
			(fill none)
			(layer "F.CrtYd")
		)
		(fp_line
			(start -0.494 0.248)
			(end -0.494 -0.25)
			(stroke
				(width 0.15)
				(type solid)
			)
			(layer "F.Fab")
		)
		(fp_line
			(start 0.504 0.248)
			(end -0.494 0.248)
			(stroke
				(width 0.15)
				(type solid)
			)
			(layer "F.Fab")
		)
		(fp_line
			(start -0.494 -0.25)
			(end 0.504 -0.25)
			(stroke
				(width 0.15)
				(type solid)
			)
			(layer "F.Fab")
		)
		(fp_line
			(start 0.504 -0.25)
			(end 0.504 0.248)
			(stroke
				(width 0.15)
				(type solid)
			)
			(layer "F.Fab")
		)
		(fp_text user "Author: Antmicro"
			(at -0.939 3.399 90)
			(layer "F.Fab")
			(hide yes)
			(effects
				(font
					(size 0.7 0.7)
					(thickness 0.15)
				)
				(justify right top)
			)
		)
		(fp_text user "License: Apache-2.0"
			(at -0.939 5.799 90)
			(layer "F.Fab")
			(hide yes)
			(effects
				(font
					(size 0.7 0.7)
					(thickness 0.15)
				)
				(justify right top)
			)
		)
		(fp_text user "${REFERENCE}"
			(at -0.939 4.599 90)
			(layer "F.Fab")
			(hide yes)
			(effects
				(font
					(size 0.7 0.7)
					(thickness 0.15)
				)
				(justify right top)
			)
		)
		(pad "1" smd roundrect
			(at -0.48 0 270)
			(size 0.59 0.64)
			(layers "F.Cu" "F.Paste" "F.Mask")
			(roundrect_rratio 0.25)
			(net 63 "/PCIE_{O}_C.TX0+")
			(pintype "passive")
		)
		(pad "2" smd roundrect
			(at 0.48 0 270)
			(size 0.59 0.64)
			(layers "F.Cu" "F.Paste" "F.Mask")
			(roundrect_rratio 0.25)
			(net 72 "/PCIE_{O}_TX0+")
			(pintype "passive")
		)
	)
	(footprint "antmicro-footprints:TSOT23-6"
		(layer "F.Cu")
		(at 144.6 111.55 90)
		(property "Reference" "U4"
			(at 0 -1.9 90)
			(layer "F.SilkS")
			(effects
				(font
					(size 0.7 0.7)
					(thickness 0.15)
				)
				(justify left bottom)
			)
		)
		(property "Value" "~"
			(at 0 2.6 90)
			(layer "F.Fab")
			(effects
				(font
					(size 0.7 0.7)
					(thickness 0.15)
				)
				(justify left bottom)
			)
		)
		(property "Footprint" "antmicro-footprints:TSOT23-6"
			(at 0 0 90)
			(layer "F.Fab")
			(hide yes)
			(effects
				(font
					(size 1.27 1.27)
					(thickness 0.15)
				)
			)
		)
		(property "Datasheet" "https://www.mouser.com/datasheet/2/115/DIOD_S_A0008958405_1-2543193.pdf"
			(at 0 0 90)
			(layer "F.Fab")
			(hide yes)
			(effects
				(font
					(size 1.27 1.27)
					(thickness 0.15)
				)
			)
		)
		(property "Description" "Power Load Distribution Switch, High Side, Active High, 1 Output, 5.5 V, 3.6 A, 0.04 ohm, TSOT-26-6"
			(at 0 0 90)
			(layer "F.Fab")
			(hide yes)
			(effects
				(font
					(size 1.27 1.27)
					(thickness 0.15)
				)
			)
		)
		(property "MPN" "AP22615AWU-7"
			(at 0 0 90)
			(unlocked yes)
			(layer "F.Fab")
			(hide yes)
			(effects
				(font
					(size 1 1)
					(thickness 0.15)
				)
			)
		)
		(property "Manufacturer" "Diodes Incorporated"
			(at 0 0 90)
			(unlocked yes)
			(layer "F.Fab")
			(hide yes)
			(effects
				(font
					(size 1 1)
					(thickness 0.15)
				)
			)
		)
		(property "Author" "Antmicro"
			(at 0 0 90)
			(unlocked yes)
			(layer "F.Fab")
			(hide yes)
			(effects
				(font
					(size 1 1)
					(thickness 0.15)
				)
			)
		)
		(property "License" "Apache-2.0"
			(at 0 0 90)
			(unlocked yes)
			(layer "F.Fab")
			(hide yes)
			(effects
				(font
					(size 1 1)
					(thickness 0.15)
				)
			)
		)
		(sheetname "Root")
		(sheetfile "jetson-orin-baseboard-oculink-expansion.kicad_sch")
		(attr smd)
		(fp_line
			(start -1 -1.5)
			(end -1 -1.375)
			(stroke
				(width 0.15)
				(type solid)
			)
			(layer "F.SilkS")
		)
		(fp_line
			(start 1 -1.497)
			(end -1 -1.5)
			(stroke
				(width 0.15)
				(type solid)
			)
			(layer "F.SilkS")
		)
		(fp_line
			(start 1 -1.497)
			(end 1 -1.375)
			(stroke
				(width 0.15)
				(type solid)
			)
			(layer "F.SilkS")
		)
		(fp_line
			(start 1 1.55)
			(end 1 1.4)
			(stroke
				(width 0.15)
				(type solid)
			)
			(layer "F.SilkS")
		)
		(fp_line
			(start 1 1.55)
			(end -1 1.55)
			(stroke
				(width 0.15)
				(type solid)
			)
			(layer "F.SilkS")
		)
		(fp_line
			(start -1 1.55)
			(end -1 1.4)
			(stroke
				(width 0.15)
				(type solid)
			)
			(layer "F.SilkS")
		)
		(fp_circle
			(center -1.44 -1.5)
			(end -1.39 -1.5)
			(stroke
				(width 0.15)
				(type solid)
			)
			(fill solid)
			(layer "F.SilkS")
		)
		(fp_rect
			(start 1.93 -1.7)
			(end -1.93 1.7)
			(stroke
				(width 0.05)
				(type solid)
			)
			(fill none)
			(layer "F.CrtYd")
		)
		(fp_line
			(start -0.45 -1.521)
			(end -0.876 -1.096)
			(stroke
				(width 0.15)
				(type solid)
			)
			(layer "F.Fab")
		)
		(fp_rect
			(start 0.875 1.528)
			(end -0.875 -1.525)
			(stroke
				(width 0.15)
				(type solid)
			)
			(fill none)
			(layer "F.Fab")
		)
		(fp_text user "${REFERENCE}"
			(at -1.93 3.8 90)
			(layer "F.Fab")
			(hide yes)
			(effects
				(font
					(size 0.7 0.7)
					(thickness 0.15)
				)
				(justify left bottom)
			)
		)
		(fp_text user "Author: Antmicro"
			(at -1.93 5 90)
			(layer "F.Fab")
			(hide yes)
			(effects
				(font
					(size 0.7 0.7)
					(thickness 0.15)
				)
				(justify left bottom)
			)
		)
		(fp_text user "License: Apache-2.0"
			(at -1.93 6.199 90)
			(layer "F.Fab")
			(hide yes)
			(effects
				(font
					(size 0.7 0.7)
					(thickness 0.15)
				)
				(justify left bottom)
			)
		)
		(pad "1" smd rect
			(at -1.301 -0.947)
			(size 0.7 1.2)
			(layers "F.Cu" "F.Paste" "F.Mask")
			(net 134 "Net-(U4-OUT)")
			(pinfunction "OUT")
			(pintype "power_out")
		)
		(pad "2" smd rect
			(at -1.301 0.004)
			(size 0.7 1.2)
			(layers "F.Cu" "F.Paste" "F.Mask")
			(net 51 "GND")
			(pinfunction "GND")
			(pintype "power_in")
		)
		(pad "3" smd rect
			(at -1.301 0.954)
			(size 0.7 1.2)
			(layers "F.Cu" "F.Paste" "F.Mask")
			(net 136 "Net-(U4-FLG)")
			(pinfunction "FLG")
			(pintype "output")
		)
		(pad "4" smd rect
			(at 1.299 0.954)
			(size 0.7 1.2)
			(layers "F.Cu" "F.Paste" "F.Mask")
			(net 23 "+3V3")
			(pinfunction "EN")
			(pintype "input")
		)
		(pad "5" smd rect
			(at 1.299 0.004)
			(size 0.7 1.2)
			(layers "F.Cu" "F.Paste" "F.Mask")
			(net 137 "Net-(U4-ISET)")
			(pinfunction "ISET")
			(pintype "passive")
		)
		(pad "6" smd rect
			(at 1.299 -0.947)
			(size 0.7 1.2)
			(layers "F.Cu" "F.Paste" "F.Mask")
			(net 23 "+3V3")
			(pinfunction "IN")
			(pintype "power_in")
		)
	)
)
